(kicad_pcb
	(version 20260206)
	(generator "pcbnew")
	(generator_version "10.0")
	(general
		(thickness 1.6)
		(legacy_teardrops no)
	)
	(paper "A4")
	(title_block
		(title "dpb — 14545-sa.0730WZS0815.brd")
		(comment 1 "Honey Badger (Wiwynn) / footprints 711-717 of 1066")
	)
	(layers
		(0 "F.Cu" signal "TOP")
		(4 "In1.Cu" signal "L2GND")
		(6 "In2.Cu" signal "L3")
		(8 "In3.Cu" signal "L4VCC")
		(10 "In4.Cu" signal "L5VCC")
		(12 "In5.Cu" signal "L6")
		(14 "In6.Cu" signal "L7GND")
		(2 "B.Cu" signal "BOTTOM")
		(9 "F.Adhes" user "F.Adhesive")
		(11 "B.Adhes" user "B.Adhesive")
		(13 "F.Paste" user "Package Geometry/Pastemask Top")
		(15 "B.Paste" user "Package Geometry/Pastemask Bottom")
		(5 "F.SilkS" user "Ref Des/Silkscreen Top")
		(7 "B.SilkS" user "Ref Des/Silkscreen Bottom")
		(1 "F.Mask" user "Board Geometry/Soldermask Top")
		(3 "B.Mask" user "Board Geometry/Soldermask Bottom")
		(17 "Dwgs.User" user "User.Drawings")
		(19 "Cmts.User" user "User.Comments")
		(21 "Eco1.User" user "User.Eco1")
		(23 "Eco2.User" user "User.Eco2")
		(25 "Edge.Cuts" user "Board Geometry/Outline")
		(27 "Margin" user)
		(31 "F.CrtYd" user "Package Geometry/Place Bound Top")
		(29 "B.CrtYd" user "Package Geometry/Place Bound Bottom")
		(35 "F.Fab" user "Ref Des/Assembly Top")
		(33 "B.Fab" user "Ref Des/Assembly Bottom")
	)
	(footprint ""
		(layer "F.Cu")
		(at 224.747582 -247.876568 90)
		(property "Reference" "R129"
			(at 0 0 90)
			(layer "F.SilkS")
			(hide yes)
			(effects
				(font
					(size 1.27 1.27)
				)
			)
		)
		(property "Value" "402R2F-GP"
			(at 0.064008 -3.993896 90)
			(unlocked yes)
			(layer "F.Fab")
			(hide yes)
			(effects
				(font
					(size 1.016 1.016)
					(thickness 0.1524)
				)
			)
		)
		(property "Device Type" "R402H16"
			(at 0.064008 -5.517896 90)
			(unlocked yes)
			(layer "F.Fab")
			(hide yes)
			(effects
				(font
					(size 1.016 1.016)
					(thickness 0.1524)
				)
			)
		)
		(duplicate_pad_numbers_are_jumpers no)
		(fp_line
			(start 0.508 -0.9398)
			(end -0.508 -0.9398)
			(stroke
				(width 0.1524)
				(type default)
			)
			(layer "F.SilkS")
		)
		(fp_line
			(start -0.508 -0.9398)
			(end -0.508 0.9398)
			(stroke
				(width 0.1524)
				(type default)
			)
			(layer "F.SilkS")
		)
		(fp_rect
			(start -0.508 0.9398)
			(end 0.508 -0.9398)
			(stroke
				(width 0)
				(type default)
			)
			(fill no)
			(layer "F.CrtYd")
		)
		(fp_rect
			(start -0.508 0.9398)
			(end 0.508 -0.9398)
			(stroke
				(width 0)
				(type default)
			)
			(fill no)
			(layer "F.Fab")
		)
		(pad "1" smd custom
			(at 0 -0.4445 90)
			(size 0.1397 0.1397)
			(layers "F.Cu" "F.Mask" "F.Paste")
			(net "P5VA_HDD2_LED")
			(options
				(clearance outline)
				(anchor circle)
			)
			(primitives
				(gr_poly
					(pts
						(arc
							(start -0.1778 -0.2794)
							(mid -0.249642 -0.249642)
							(end -0.2794 -0.1778)
						)
						(arc
							(start -0.2794 0.1778)
							(mid -0.249642 0.249642)
							(end -0.1778 0.2794)
						)
						(arc
							(start 0.1778 0.2794)
							(mid 0.249642 0.249642)
							(end 0.2794 0.1778)
						)
						(arc
							(start 0.2794 -0.1778)
							(mid 0.249642 -0.249642)
							(end 0.1778 -0.2794)
						)
					)
					(width 0)
					(fill yes)
				)
			)
		)
		(pad "2" smd custom
			(at 0 0.4445 90)
			(size 0.1397 0.1397)
			(layers "F.Cu" "F.Mask" "F.Paste")
			(net "DRV_ACT_2")
			(options
				(clearance outline)
				(anchor circle)
			)
			(primitives
				(gr_poly
					(pts
						(arc
							(start -0.1778 -0.2794)
							(mid -0.249642 -0.249642)
							(end -0.2794 -0.1778)
						)
						(arc
							(start -0.2794 0.1778)
							(mid -0.249642 0.249642)
							(end -0.1778 0.2794)
						)
						(arc
							(start 0.1778 0.2794)
							(mid 0.249642 0.249642)
							(end 0.2794 0.1778)
						)
						(arc
							(start 0.2794 -0.1778)
							(mid 0.249642 -0.249642)
							(end 0.1778 -0.2794)
						)
					)
					(width 0)
					(fill yes)
				)
			)
		)
	)
	(footprint ""
		(layer "F.Cu")
		(at 20.193254 -156.3243 -90)
		(property "Reference" "R285"
			(at 0 0 270)
			(layer "F.SilkS")
			(hide yes)
			(effects
				(font
					(size 1.27 1.27)
				)
			)
		)
		(property "Value" "330R2F-GP"
			(at 0.064008 -3.993896 270)
			(unlocked yes)
			(layer "F.Fab")
			(hide yes)
			(effects
				(font
					(size 1.016 1.016)
					(thickness 0.1524)
				)
			)
		)
		(property "Device Type" "R402H16"
			(at 0.064008 -5.517896 270)
			(unlocked yes)
			(layer "F.Fab")
			(hide yes)
			(effects
				(font
					(size 1.016 1.016)
					(thickness 0.1524)
				)
			)
		)
		(duplicate_pad_numbers_are_jumpers no)
		(fp_line
			(start -0.508 -0.9398)
			(end -0.508 0.9398)
			(stroke
				(width 0.1524)
				(type default)
			)
			(layer "F.SilkS")
		)
		(fp_line
			(start 0.508 -0.9398)
			(end -0.508 -0.9398)
			(stroke
				(width 0.1524)
				(type default)
			)
			(layer "F.SilkS")
		)
		(fp_rect
			(start -0.508 0.9398)
			(end 0.508 -0.9398)
			(stroke
				(width 0)
				(type default)
			)
			(fill no)
			(layer "F.CrtYd")
		)
		(fp_rect
			(start -0.508 0.9398)
			(end 0.508 -0.9398)
			(stroke
				(width 0)
				(type default)
			)
			(fill no)
			(layer "F.Fab")
		)
		(pad "1" smd custom
			(at 0 -0.4445 270)
			(size 0.1397 0.1397)
			(layers "F.Cu" "F.Mask" "F.Paste")
			(net "P3V3_HDD13_LED")
			(options
				(clearance outline)
				(anchor circle)
			)
			(primitives
				(gr_poly
					(pts
						(arc
							(start -0.1778 -0.2794)
							(mid -0.249642 -0.249642)
							(end -0.2794 -0.1778)
						)
						(arc
							(start -0.2794 0.1778)
							(mid -0.249642 0.249642)
							(end -0.1778 0.2794)
						)
						(arc
							(start 0.1778 0.2794)
							(mid 0.249642 0.249642)
							(end 0.2794 0.1778)
						)
						(arc
							(start 0.2794 -0.1778)
							(mid 0.249642 -0.249642)
							(end 0.1778 -0.2794)
						)
					)
					(width 0)
					(fill yes)
				)
			)
		)
		(pad "2" smd custom
			(at 0 0.4445 270)
			(size 0.1397 0.1397)
			(layers "F.Cu" "F.Mask" "F.Paste")
			(net "FLT_HDD13")
			(options
				(clearance outline)
				(anchor circle)
			)
			(primitives
				(gr_poly
					(pts
						(arc
							(start -0.1778 -0.2794)
							(mid -0.249642 -0.249642)
							(end -0.2794 -0.1778)
						)
						(arc
							(start -0.2794 0.1778)
							(mid -0.249642 0.249642)
							(end -0.1778 0.2794)
						)
						(arc
							(start 0.1778 0.2794)
							(mid 0.249642 0.249642)
							(end 0.2794 0.1778)
						)
						(arc
							(start 0.2794 -0.1778)
							(mid 0.249642 -0.249642)
							(end 0.1778 -0.2794)
						)
					)
					(width 0)
					(fill yes)
				)
			)
		)
	)
	(footprint ""
		(layer "F.Cu")
		(at 14.604746 -51.7017 -90)
		(property "Reference" "R296"
			(at 0 0 270)
			(layer "F.SilkS")
			(hide yes)
			(effects
				(font
					(size 1.27 1.27)
				)
			)
		)
		(property "Value" "10KR2F-2-GP"
			(at 0.064008 -3.993896 270)
			(unlocked yes)
			(layer "F.Fab")
			(hide yes)
			(effects
				(font
					(size 1.016 1.016)
					(thickness 0.1524)
				)
			)
		)
		(property "Device Type" "R402H16"
			(at 0.064008 -5.517896 270)
			(unlocked yes)
			(layer "F.Fab")
			(hide yes)
			(effects
				(font
					(size 1.016 1.016)
					(thickness 0.1524)
				)
			)
		)
		(duplicate_pad_numbers_are_jumpers no)
		(fp_line
			(start -0.508 -0.9398)
			(end -0.508 0.9398)
			(stroke
				(width 0.1524)
				(type default)
			)
			(layer "F.SilkS")
		)
		(fp_line
			(start 0.508 -0.9398)
			(end -0.508 -0.9398)
			(stroke
				(width 0.1524)
				(type default)
			)
			(layer "F.SilkS")
		)
		(fp_rect
			(start -0.508 0.9398)
			(end 0.508 -0.9398)
			(stroke
				(width 0)
				(type default)
			)
			(fill no)
			(layer "F.CrtYd")
		)
		(fp_rect
			(start -0.508 0.9398)
			(end 0.508 -0.9398)
			(stroke
				(width 0)
				(type default)
			)
			(fill no)
			(layer "F.Fab")
		)
		(pad "1" smd custom
			(at 0 -0.4445 270)
			(size 0.1397 0.1397)
			(layers "F.Cu" "F.Mask" "F.Paste")
			(net "P5VC")
			(options
				(clearance outline)
				(anchor circle)
			)
			(primitives
				(gr_poly
					(pts
						(arc
							(start -0.1778 -0.2794)
							(mid -0.249642 -0.249642)
							(end -0.2794 -0.1778)
						)
						(arc
							(start -0.2794 0.1778)
							(mid -0.249642 0.249642)
							(end -0.1778 0.2794)
						)
						(arc
							(start 0.1778 0.2794)
							(mid 0.249642 0.249642)
							(end 0.2794 0.1778)
						)
						(arc
							(start 0.2794 -0.1778)
							(mid 0.249642 -0.249642)
							(end 0.1778 -0.2794)
						)
					)
					(width 0)
					(fill yes)
				)
			)
		)
		(pad "2" smd custom
			(at 0 0.4445 270)
			(size 0.1397 0.1397)
			(layers "F.Cu" "F.Mask" "F.Paste")
			(net "DRIVE_ACT_14")
			(options
				(clearance outline)
				(anchor circle)
			)
			(primitives
				(gr_poly
					(pts
						(arc
							(start -0.1778 -0.2794)
							(mid -0.249642 -0.249642)
							(end -0.2794 -0.1778)
						)
						(arc
							(start -0.2794 0.1778)
							(mid -0.249642 0.249642)
							(end -0.1778 0.2794)
						)
						(arc
							(start 0.1778 0.2794)
							(mid 0.249642 0.249642)
							(end 0.2794 0.1778)
						)
						(arc
							(start 0.2794 -0.1778)
							(mid 0.249642 -0.249642)
							(end 0.1778 -0.2794)
						)
					)
					(width 0)
					(fill yes)
				)
			)
		)
	)
	(footprint ""
		(layer "F.Cu")
		(at 78.358746 -190.5127 90)
		(property "Reference" "R224"
			(at 0 0 90)
			(layer "F.SilkS")
			(hide yes)
			(effects
				(font
					(size 1.27 1.27)
				)
			)
		)
		(property "Value" "0R2J-2-GP"
			(at 0.064008 -3.993896 90)
			(unlocked yes)
			(layer "F.Fab")
			(hide yes)
			(effects
				(font
					(size 1.016 1.016)
					(thickness 0.1524)
				)
			)
		)
		(property "Device Type" "R402H16"
			(at 0.064008 -5.517896 90)
			(unlocked yes)
			(layer "F.Fab")
			(hide yes)
			(effects
				(font
					(size 1.016 1.016)
					(thickness 0.1524)
				)
			)
		)
		(duplicate_pad_numbers_are_jumpers no)
		(fp_line
			(start 0.508 -0.9398)
			(end -0.508 -0.9398)
			(stroke
				(width 0.1524)
				(type default)
			)
			(layer "F.SilkS")
		)
		(fp_line
			(start -0.508 -0.9398)
			(end -0.508 0.9398)
			(stroke
				(width 0.1524)
				(type default)
			)
			(layer "F.SilkS")
		)
		(fp_rect
			(start -0.508 0.9398)
			(end 0.508 -0.9398)
			(stroke
				(width 0)
				(type default)
			)
			(fill no)
			(layer "F.CrtYd")
		)
		(fp_rect
			(start -0.508 0.9398)
			(end 0.508 -0.9398)
			(stroke
				(width 0)
				(type default)
			)
			(fill no)
			(layer "F.Fab")
		)
		(pad "1" smd custom
			(at 0 -0.4445 90)
			(size 0.1397 0.1397)
			(layers "F.Cu" "F.Mask" "F.Paste")
			(net "SW_PWR_HDD8")
			(options
				(clearance outline)
				(anchor circle)
			)
			(primitives
				(gr_poly
					(pts
						(arc
							(start -0.1778 -0.2794)
							(mid -0.249642 -0.249642)
							(end -0.2794 -0.1778)
						)
						(arc
							(start -0.2794 0.1778)
							(mid -0.249642 0.249642)
							(end -0.1778 0.2794)
						)
						(arc
							(start 0.1778 0.2794)
							(mid 0.249642 0.249642)
							(end 0.2794 0.1778)
						)
						(arc
							(start 0.2794 -0.1778)
							(mid 0.249642 -0.249642)
							(end 0.1778 -0.2794)
						)
					)
					(width 0)
					(fill yes)
				)
			)
		)
		(pad "2" smd custom
			(at 0 0.4445 90)
			(size 0.1397 0.1397)
			(layers "F.Cu" "F.Mask" "F.Paste")
			(net "SW_PWR_R_HDD8")
			(options
				(clearance outline)
				(anchor circle)
			)
			(primitives
				(gr_poly
					(pts
						(arc
							(start -0.1778 -0.2794)
							(mid -0.249642 -0.249642)
							(end -0.2794 -0.1778)
						)
						(arc
							(start -0.2794 0.1778)
							(mid -0.249642 0.249642)
							(end -0.1778 0.2794)
						)
						(arc
							(start 0.1778 0.2794)
							(mid 0.249642 0.249642)
							(end 0.2794 0.1778)
						)
						(arc
							(start 0.2794 -0.1778)
							(mid 0.249642 -0.249642)
							(end 0.1778 -0.2794)
						)
					)
					(width 0)
					(fill yes)
				)
			)
		)
	)
	(footprint ""
		(layer "F.Cu")
		(at 30.733746 -298.9707 180)
		(property "Reference" "C226"
			(at 0 0 180)
			(layer "F.SilkS")
			(hide yes)
			(effects
				(font
					(size 1.27 1.27)
				)
			)
		)
		(property "Value" "SC10U25V6KX-1GP"
			(at -0.0762 -5.1308 180)
			(unlocked yes)
			(layer "F.Fab")
			(hide yes)
			(effects
				(font
					(size 1.016 1.016)
					(thickness 0.1524)
				)
			)
		)
		(property "Device Type" "C1206H71"
			(at -0.127 -6.6548 180)
			(unlocked yes)
			(layer "F.Fab")
			(hide yes)
			(effects
				(font
					(size 1.016 1.016)
					(thickness 0.1524)
				)
			)
		)
		(duplicate_pad_numbers_are_jumpers no)
		(fp_line
			(start 1.016 2.2352)
			(end -1.016 2.2352)
			(stroke
				(width 0.1524)
				(type default)
			)
			(layer "F.SilkS")
		)
		(fp_line
			(start 1.016 0.8382)
			(end 1.016 2.2352)
			(stroke
				(width 0.1524)
				(type default)
			)
			(layer "F.SilkS")
		)
		(fp_line
			(start 1.016 -2.2352)
			(end 1.016 -0.8382)
			(stroke
				(width 0.1524)
				(type default)
			)
			(layer "F.SilkS")
		)
		(fp_line
			(start -1.016 2.2352)
			(end -1.016 0.8382)
			(stroke
				(width 0.1524)
				(type default)
			)
			(layer "F.SilkS")
		)
		(fp_line
			(start -1.016 -0.8382)
			(end -1.016 -2.2352)
			(stroke
				(width 0.1524)
				(type default)
			)
			(layer "F.SilkS")
		)
		(fp_line
			(start -1.016 -2.2352)
			(end 1.016 -2.2352)
			(stroke
				(width 0.1524)
				(type default)
			)
			(layer "F.SilkS")
		)
		(fp_rect
			(start -1.0922 2.3114)
			(end 1.0922 -2.3114)
			(stroke
				(width 0)
				(type default)
			)
			(fill no)
			(layer "F.CrtYd")
		)
		(fp_poly
			(pts
				(xy 1.0922 -2.3114) (xy 1.0922 2.3114) (xy -1.0922 2.3114) (xy -1.0922 -2.3114)
			)
			(stroke
				(width 0)
				(type default)
			)
			(fill no)
			(layer "F.Fab")
		)
		(pad "1" smd rect
			(at 0 -1.397 180)
			(size 1.651 1.27)
			(layers "F.Cu" "F.Mask" "F.Paste")
			(net "P12V_HDD7")
		)
		(pad "2" smd rect
			(at 0 1.397 180)
			(size 1.651 1.27)
			(layers "F.Cu" "F.Mask" "F.Paste")
			(net "GND")
		)
	)
	(footprint ""
		(layer "F.Cu")
		(at 242.696746 -22.7457 90)
		(property "Reference" "PR1"
			(at 0 0 90)
			(layer "F.SilkS")
			(hide yes)
			(effects
				(font
					(size 1.27 1.27)
				)
			)
		)
		(property "Value" "0R3J-0-U-GP"
			(at -0.0254 -2.5146 90)
			(unlocked yes)
			(layer "F.Fab")
			(hide yes)
			(effects
				(font
					(size 1.016 1.016)
					(thickness 0.1524)
				)
			)
		)
		(property "Device Type" "R603H22"
			(at -0.0254 -4.0386 90)
			(unlocked yes)
			(layer "F.Fab")
			(hide yes)
			(effects
				(font
					(size 1.016 1.016)
					(thickness 0.1524)
				)
			)
		)
		(duplicate_pad_numbers_are_jumpers no)
		(fp_line
			(start 0.2032 0)
			(end 0.4826 0)
			(stroke
				(width 0.2032)
				(type default)
			)
			(layer "F.SilkS")
		)
		(fp_line
			(start -0.4826 0)
			(end -0.2032 0)
			(stroke
				(width 0.2032)
				(type default)
			)
			(layer "F.SilkS")
		)
		(fp_rect
			(start -0.5842 1.3335)
			(end 0.5842 -1.3335)
			(stroke
				(width 0)
				(type default)
			)
			(fill no)
			(layer "F.CrtYd")
		)
		(fp_rect
			(start -0.5842 1.3335)
			(end 0.5842 -1.3335)
			(stroke
				(width 0)
				(type default)
			)
			(fill no)
			(layer "F.Fab")
		)
		(pad "1" smd custom
			(at 0 -0.762 90)
			(size 0.2159 0.2159)
			(layers "F.Cu" "F.Mask" "F.Paste")
			(net "P5VA_12VIN")
			(options
				(clearance outline)
				(anchor circle)
			)
			(primitives
				(gr_poly
					(pts
						(arc
							(start -0.3302 -0.4318)
							(mid -0.402042 -0.402042)
							(end -0.4318 -0.3302)
						)
						(arc
							(start -0.4318 0.3302)
							(mid -0.402042 0.402042)
							(end -0.3302 0.4318)
						)
						(arc
							(start 0.3302 0.4318)
							(mid 0.402042 0.402042)
							(end 0.4318 0.3302)
						)
						(arc
							(start 0.4318 -0.3302)
							(mid 0.402042 -0.402042)
							(end 0.3302 -0.4318)
						)
					)
					(width 0)
					(fill yes)
				)
			)
		)
		(pad "2" smd custom
			(at 0 0.762 90)
			(size 0.2159 0.2159)
			(layers "F.Cu" "F.Mask" "F.Paste")
			(net "P5VA_VDD")
			(options
				(clearance outline)
				(anchor circle)
			)
			(primitives
				(gr_poly
					(pts
						(arc
							(start -0.3302 -0.4318)
							(mid -0.402042 -0.402042)
							(end -0.4318 -0.3302)
						)
						(arc
							(start -0.4318 0.3302)
							(mid -0.402042 0.402042)
							(end -0.3302 0.4318)
						)
						(arc
							(start 0.3302 0.4318)
							(mid 0.402042 0.402042)
							(end 0.4318 0.3302)
						)
						(arc
							(start 0.4318 -0.3302)
							(mid 0.402042 -0.402042)
							(end 0.3302 -0.4318)
						)
					)
					(width 0)
					(fill yes)
				)
			)
		)
	)
	(footprint ""
		(layer "F.Cu")
		(at 215.496902 -282.730702 180)
		(property "Reference" "C139"
			(at 0 0 180)
			(layer "F.SilkS")
			(hide yes)
			(effects
				(font
					(size 1.27 1.27)
				)
			)
		)
		(property "Value" "SC10U16V6KX-2GP"
			(at -0.0762 -5.1308 180)
			(unlocked yes)
			(layer "F.Fab")
			(hide yes)
			(effects
				(font
					(size 1.016 1.016)
					(thickness 0.1524)
				)
			)
		)
		(property "Device Type" "C1206H71"
			(at -0.127 -6.6548 180)
			(unlocked yes)
			(layer "F.Fab")
			(hide yes)
			(effects
				(font
					(size 1.016 1.016)
					(thickness 0.1524)
				)
			)
		)
		(duplicate_pad_numbers_are_jumpers no)
		(fp_line
			(start 1.016 2.2352)
			(end -1.016 2.2352)
			(stroke
				(width 0.1524)
				(type default)
			)
			(layer "F.SilkS")
		)
		(fp_line
			(start 1.016 0.8382)
			(end 1.016 2.2352)
			(stroke
				(width 0.1524)
				(type default)
			)
			(layer "F.SilkS")
		)
		(fp_line
			(start 1.016 -2.2352)
			(end 1.016 -0.8382)
			(stroke
				(width 0.1524)
				(type default)
			)
			(layer "F.SilkS")
		)
		(fp_line
			(start -1.016 2.2352)
			(end -1.016 0.8382)
			(stroke
				(width 0.1524)
				(type default)
			)
			(layer "F.SilkS")
		)
		(fp_line
			(start -1.016 -0.8382)
			(end -1.016 -2.2352)
			(stroke
				(width 0.1524)
				(type default)
			)
			(layer "F.SilkS")
		)
		(fp_line
			(start -1.016 -2.2352)
			(end 1.016 -2.2352)
			(stroke
				(width 0.1524)
				(type default)
			)
			(layer "F.SilkS")
		)
		(fp_rect
			(start -1.0922 2.3114)
			(end 1.0922 -2.3114)
			(stroke
				(width 0)
				(type default)
			)
			(fill no)
			(layer "F.CrtYd")
		)
		(fp_poly
			(pts
				(xy 1.0922 -2.3114) (xy 1.0922 2.3114) (xy -1.0922 2.3114) (xy -1.0922 -2.3114)
			)
			(stroke
				(width 0)
				(type default)
			)
			(fill no)
			(layer "F.Fab")
		)
		(pad "1" smd rect
			(at 0 -1.397 180)
			(size 1.651 1.27)
			(layers "F.Cu" "F.Mask" "F.Paste")
			(net "P5V_HDD2")
		)
		(pad "2" smd rect
			(at 0 1.397 180)
			(size 1.651 1.27)
			(layers "F.Cu" "F.Mask" "F.Paste")
			(net "GND")
		)
	)
)
